FILE_TYPE = CONNECTIVITY;
{Allegro Design Entry HDL 17.2-2016 S081 (4005846) 1/11/2022}
"PAGE_NUMBER" = 133;
0"NC";
1"P3V3_AUX\g";
2"PVNN_TERM_CPU0\g";
3"P3V3_AUX\g";
4"P1V8_PCH_AUX\g"$PHYS_NET_NAME"P1V8_PCH_AUX"CDS_PHYS_NET_NAME"P1V8_PCH_AUX";
5"P1V05_PCH_AUX\g"$PHYS_NET_NAME"P1V8_PCH_AUX"CDS_PHYS_NET_NAME"P1V8_PCH_AUX";
6"P3V3_AUX\g";
7"GND\g";
8"GND\g";
9"GND\g"PHYS_NET_NAME"GND"VOLTAGE"0"CDS_PHYS_NET_NAME"GND";
10"GND\g";
11"GND\g";
12"GND\g";
13"GND\g";
14"GND\g";
15"GND\g";
16"GND\g";
17"SMB_HOST_3V3AUX_SCL_R4"CDS_PHYS_NET_NAME"PD_PIROM_CPU0_ADDR0";
18"SMB_HOST_3V3AUX_SDA_R4"CDS_PHYS_NET_NAME"PD_PIROM_CPU0_ADDR0";
19"SMB_HOST_3V3AUX_XDP_R_SCL"CDS_PHYS_NET_NAME"PD_PIROM_CPU0_ADDR0";
20"SMB_HOST_3V3AUX_XDP_R_SDA"CDS_PHYS_NET_NAME"PD_PIROM_CPU0_ADDR0";
21"JTAG_DBP_BOOT_HALT_N"CDS_PHYS_NET_NAME"PD_PIROM_CPU0_ADDR0";
22"NC_DBP_P30"CDS_PHYS_NET_NAME"NC_DBP_P34";
23"NC_DBP_P28"CDS_PHYS_NET_NAME"NC_DBP_P34";
24"NC_DBP_P26"CDS_PHYS_NET_NAME"NC_DBP_P34";
25"NC_DBP_P22"CDS_PHYS_NET_NAME"NC_DBP_P34";
26"NC_DBP_P18"CDS_PHYS_NET_NAME"NC_DBP_P34";
27"JTAG_DBP_TDO";
28"JTAG_RST_DBP_RST_CO_N"CDS_PHYS_NET_NAME"PD_PIROM_CPU0_ADDR0";
29"JTAG_DBP_PRDY_R1_N"CDS_PHYS_NET_NAME"PD_PIROM_CPU0_ADDR0";
30"JTAG_DBP_PMODE"CDS_PHYS_NET_NAME"TRC_PCH_PTI1_CLK";
31"JTAG_DBP_TDI_R"CDS_PHYS_NET_NAME"PD_PIROM_CPU0_ADDR0";
32"JTAG_DBP_CPU_GTL_TCK_R"CDS_PHYS_NET_NAME"PD_PIROM_CPU0_ADDR0";
33"JTAG_DBP_TMS_R"CDS_PHYS_NET_NAME"PD_PIROM_CPU0_ADDR0";
34"PD_TRST_P3"CDS_PHYS_NET_NAME"PD_PIROM_CPU0_ADDR0";
35"FM_CPU_FBRK_DEBUG_N"CDS_PHYS_NET_NAME"PD_PIROM_CPU0_ADDR0";
36"NC_DBP_P54"CDS_PHYS_NET_NAME"PD_PIROM_CPU0_ADDR0";
37"NC_DBP_P56"CDS_PHYS_NET_NAME"PD_PIROM_CPU0_ADDR0";
38"JTAG_DBP_CPU_HOOK8_MBP2_GTL_N"CDS_PHYS_NET_NAME"PD_PIROM_CPU0_ADDR0";
39"JTAG_TRC_PCH_PTI1_CLK"CDS_PHYS_NET_NAME"TRC_PCH_PTI1_CLK";
40"SMB_HOST_3V3AUX_XDP_R_SCL"CDS_PHYS_NET_NAME"PD_PIROM_CPU0_ADDR0";
41"SMB_HOST_3V3AUX_XDP_R_SDA"CDS_PHYS_NET_NAME"PD_PIROM_CPU0_ADDR0";
42"NC_DBP_P46"CDS_PHYS_NET_NAME"PD_PIROM_CPU0_ADDR0";
43"NC_DBP_P44"CDS_PHYS_NET_NAME"PD_PIROM_CPU0_ADDR0";
44"JTAG_DBP_POWER_BTN_N"CDS_PHYS_NET_NAME"PD_PIROM_CPU0_ADDR0";
45"JTAG_RST_DBP_RSMRST_N"CDS_PHYS_NET_NAME"PD_PIROM_CPU0_ADDR0";
46"NC_DBP_P24"CDS_PHYS_NET_NAME"NC_DBP_P34";
47"NC_DBP_P32"CDS_PHYS_NET_NAME"PD_PIROM_CPU0_ADDR0";
48"NC_DBP_P34"CDS_PHYS_NET_NAME"PD_PIROM_CPU0_ADDR0";
49"FM_CPU_FBRK_DEBUG_R_N";
50"JTAG_DBP_TDO_R"CDS_PHYS_NET_NAME"PD_PIROM_CPU0_ADDR0";
51"NC_MIPI60_P9"CDS_PHYS_NET_NAME"TRC_PCH_PTI1_CLK";
52"JTAG_DBP_PREQ_N_R"CDS_PHYS_NET_NAME"PD_PIROM_CPU0_ADDR0";
53"JTAG_TRC_PCH_PTI0_CLK"CDS_PHYS_NET_NAME"TRC_PCH_PTI1_CLK";
54"JTAG_DBP_PCH_DEBUG_CONSENT_N"CDS_PHYS_NET_NAME"PD_PIROM_CPU0_ADDR0";
55"JTAG_DBP_PRESENT_R_N"CDS_PHYS_NET_NAME"PD_PIROM_CPU0_ADDR0";
56"JTAG_TRC_PCH_PTI<0>"CDS_PHYS_NET_NAME"TRC_PCH_PTI<0>";
57"NC_DBP_P20"CDS_PHYS_NET_NAME"NC_DBP_P34";
58"JTAG_TRC_PCH_PTI<1>"CDS_PHYS_NET_NAME"TRC_PCH_PTI<1>";
59"JTAG_TRC_PCH_PTI<2>"CDS_PHYS_NET_NAME"TRC_PCH_PTI<2>";
60"JTAG_TRC_PCH_PTI<3>"CDS_PHYS_NET_NAME"TRC_PCH_PTI<3>";
61"JTAG_TRC_PCH_PTI<4>"CDS_PHYS_NET_NAME"TRC_PCH_PTI<4>";
62"JTAG_TRC_PCH_PTI<5>"CDS_PHYS_NET_NAME"TRC_PCH_PTI<5>";
63"JTAG_TRC_PCH_PTI<6>"CDS_PHYS_NET_NAME"TRC_PCH_PTI<6>";
64"JTAG_TRC_PCH_PTI<7>"CDS_PHYS_NET_NAME"TRC_PCH_PTI<7>";
65"JTAG_TRC_PCH_PTI<8>"CDS_PHYS_NET_NAME"TRC_PCH_PTI<8>";
66"JTAG_TRC_PCH_PTI<9>"CDS_PHYS_NET_NAME"TRC_PCH_PTI<9>";
67"JTAG_TRC_PCH_PTI<10>"CDS_PHYS_NET_NAME"TRC_PCH_PTI<10>";
68"JTAG_TRC_PCH_PTI<11>"CDS_PHYS_NET_NAME"TRC_PCH_PTI<11>";
69"JTAG_TRC_PCH_PTI<12>"CDS_PHYS_NET_NAME"TRC_PCH_PTI<12>";
70"JTAG_TRC_PCH_PTI<13>"CDS_PHYS_NET_NAME"TRC_PCH_PTI<13>";
71"JTAG_TRC_PCH_PTI<14>"CDS_PHYS_NET_NAME"TRC_PCH_PTI<14>";
72"JTAG_TRC_PCH_PTI<15>"CDS_PHYS_NET_NAME"TRC_PCH_PTI<15>";
73"JTAG_DBP_TCK_R_TCK"CDS_PHYS_NET_NAME"PD_PIROM_CPU0_ADDR0";
74"JTAG_DBP_CPU_HOOK9_MBP3_GTL_N"CDS_PHYS_NET_NAME"PD_PIROM_CPU0_ADDR0";
75"JTAG_DBP_PREQ_N";
76"JTAG_DBP_BOOT_HALT_N"CDS_PHYS_NET_NAME"TRC_PCH_PTI1_CLK";
77"JTAG_RST_DBP_RSMRST_N"CDS_PHYS_NET_NAME"TRC_PCH_PTI1_CLK";
78"JTAG_DBP_PCH_DEBUG_CONSENT_N"CDS_PHYS_NET_NAME"TRC_PCH_PTI1_CLK";
79"FM_ADR_MODE0"CDS_PHYS_NET_NAME"TRC_PCH_PTI1_CLK";
80"JTAG_DBP_POWER_BTN_N"CDS_PHYS_NET_NAME"TRC_PCH_PTI1_CLK";
81"JTAG_RST_DBP_RST_CO_N"CDS_PHYS_NET_NAME"TRC_PCH_PTI1_CLK";
82"FM_BMC_DBP_PRESENT_R_N"CDS_PHYS_NET_NAME"TRC_PCH_PTI1_CLK";
83"FM_PCH_CONSENT_STRAP_N"CDS_PHYS_NET_NAME"TRC_PCH_PTI1_CLK";
84"RST_RSMRST_PCH_N"CDS_PHYS_NET_NAME"TRC_PCH_PTI1_CLK";
85"JTAG_DBP_PRESENT_R_N"CDS_PHYS_NET_NAME"TRC_PCH_PTI1_CLK";
86"JTAG_DBP_CPU_GTL_TCK"CDS_PHYS_NET_NAME"TRC_PCH_PTI1_CLK";
87"JTAG_DBP_TCK_PCH"CDS_PHYS_NET_NAME"JTAG_DBP_CPU_GTL_TCK";
88"JTAG_DBP_PRDY_N"CDS_PHYS_NET_NAME"PD_PIROM_CPU0_ADDR0";
89"JTAG_DBP_CPU_GTL_TCK"CDS_PHYS_NET_NAME"PD_PIROM_CPU0_ADDR0";
90"JTAG_DBP_TDI"CDS_PHYS_NET_NAME"PD_PIROM_CPU0_ADDR0";
91"JTAG_DBP_TMS";
%"Q_RES"
"1","(1625,2975)","0","pure_quanta","I10";
;
PART_NUMBER"CS01002FB07"
MATERIAL"CHIP"
VALUE"10"
TOLERANCE"1%"
PACK_TYPE"0402LF"
WATTAGE"1/16W"
$LOCATION"R777"
CDS_LIB"pure_quanta"
CDS_LOCATION"R777"
$SEC"1"
CDS_SEC"1";
"B"
$PN"2"75;
"A"
$PN"1"52;
%"Q_CAP"
"1","(-125,3500)","2","pure_quanta","I100";
;
PART_NUMBER"CH5104KEB02"
PACK_TYPE"C0402"
MATERIAL"X6S"
VALUE"1UF"
VOLTAGE"25V"
TOLERANCE"10%"
$LOCATION"C547"
CDS_LIB"pure_quanta"
CDS_LOCATION"C547"
$SEC"1"
CDS_SEC"1";
"B"
$PN"2"13;
"A"
$PN"1"5;
%"UNIVERSAL_GND"
"1","(-125,3300)","0","logical_power","I101";
;
CDS_LIB"logical_power"
HDL_POWER"GND";
"A"13;
%"Q_RES"
"2","(2650,2650)","0","pure_quanta","I102";
;
PART_NUMBER"CS31002FB08"
PACK_TYPE"0402LF"
TOLERANCE"1%"
VALUE"10K"
MATERIAL"CHIP"
WATTAGE"1/16W"
$LOCATION"R769"
CDS_LIB"pure_quanta"
CDS_LOCATION"R769"
$SEC"1"
CDS_SEC"1";
"A"
$PN"1"34;
"B"
$PN"2"7;
%"UNIVERSAL_GND"
"1","(2650,2425)","0","logical_power","I103";
;
CDS_LIB"logical_power"
HDL_POWER"GND";
"A"7;
%"UNIVERSAL_GND"
"1","(1825,1325)","0","logical_power","I104";
;
CDS_LIB"logical_power"
HDL_POWER"GND";
"A"14;
%"Q_CAP"
"1","(1825,1525)","0","pure_quanta","I105";
;
PART_NUMBER"CH5104KEB02"
VOLTAGE"25V"
MATERIAL"X6S"
TOLERANCE"10%"
VALUE"1UF"
PACK_TYPE"C0402"
$LOCATION"C551"
CDS_LIB"pure_quanta"
CDS_LOCATION"C551"
$SEC"1"
CDS_SEC"1";
"B"
$PN"2"14;
"A"
$PN"1"3;
%"UNIVERSAL_POWER"
"1","(-125,50)","0","logical_power","I109";
;
HDL_POWER"P3V3_AUX"
CDS_LIB"logical_power";
"A"1;
%"UNIVERSAL_POWER"
"1","(725,3750)","0","logical_power","I11";
;
HDL_POWER"P1V8_PCH_AUX"
CDS_LIB"logical_power";
"A"4;
%"Q_RES"
"2","(-125,-250)","0","pure_quanta","I111";
;
PART_NUMBER"CS21002FB06"
PACK_TYPE"0402LF"
VALUE"1K"
TOLERANCE"1%"
MATERIAL"EMPTY"
WATTAGE"1/16W"
$LOCATION"R766"
CDS_LIB"pure_quanta"
CDS_LOCATION"R766"
$SEC"1"
CDS_SEC"1";
"A"
$PN"1"1;
"B"
$PN"2"80;
%"Q_RES"
"2","(300,-250)","0","pure_quanta","I112";
;
PART_NUMBER"CS21002FB06"
WATTAGE"1/16W"
TOLERANCE"1%"
VALUE"1K"
MATERIAL"CHIP"
PACK_TYPE"0402LF"
$LOCATION"R768"
CDS_LIB"pure_quanta"
CDS_LOCATION"R768"
$SEC"1"
CDS_SEC"1";
"A"
$PN"1"1;
"B"
$PN"2"85;
%"Q_RES"
"2","(100,-250)","0","pure_quanta","I113";
;
PART_NUMBER"CS21002FB06"
PACK_TYPE"0402LF"
MATERIAL"CHIP"
WATTAGE"1/16W"
TOLERANCE"1%"
VALUE"1K"
$LOCATION"R767"
CDS_LIB"pure_quanta"
CDS_LOCATION"R767"
$SEC"1"
CDS_SEC"1";
"A"
$PN"1"1;
"B"
$PN"2"81;
%"Q_RES"
"1","(625,-875)","0","pure_quanta","I118";
;
PART_NUMBER"CS21002FB06"
MATERIAL"CHIP"
PACK_TYPE"0402LF"
WATTAGE"1/16W"
TOLERANCE"1%"
VALUE"1K"
$LOCATION"R772"
CDS_LIB"pure_quanta"
CDS_LOCATION"R772"
$SEC"1"
CDS_SEC"1";
"B"
$PN"2"84;
"A"
$PN"1"77;
%"UNIVERSAL_GND"
"1","(725,1500)","0","logical_power","I12";
;
CDS_LIB"logical_power"
HDL_POWER"GND";
"A"8;
%"Q_RES"
"1","(625,-800)","0","pure_quanta","I120";
;
PART_NUMBER"CS21002FB06"
TOLERANCE"1%"
WATTAGE"1/16W"
VALUE"1K"
PACK_TYPE"0402LF"
MATERIAL"CHIP"
$LOCATION"R771"
CDS_LIB"pure_quanta"
CDS_LOCATION"R771"
$SEC"1"
CDS_SEC"1";
"B"
$PN"2"83;
"A"
$PN"1"78;
%"Q_RES"
"1","(625,-950)","0","pure_quanta","I124";
;
PART_NUMBER"CS21002FB06"
VALUE"1K"
TOLERANCE"1%"
WATTAGE"1/16W"
PACK_TYPE"0402LF"
MATERIAL"CHIP"
$LOCATION"R773"
CDS_LIB"pure_quanta"
CDS_LOCATION"R773"
$SEC"1"
CDS_SEC"1";
"B"
$PN"2"79;
"A"
$PN"1"76;
%"UNIVERSAL_GND"
"1","(-125,-1475)","0","logical_power","I126";
;
CDS_LIB"logical_power"
HDL_POWER"GND";
"A"11;
%"UNIVERSAL_GND"
"1","(100,-1475)","0","logical_power","I128";
;
CDS_LIB"logical_power"
HDL_POWER"GND";
"A"10;
%"Q_CAP"
"1","(100,-1225)","0","pure_quanta","I129";
;
PART_NUMBER"CH4104K1B00"
VALUE"0.1UF"
VOLTAGE"25V"
PACK_TYPE"0402"
MATERIAL"X7R"
TOLERANCE"10%"
$LOCATION"C549"
CDS_LIB"pure_quanta"
CDS_LOCATION"C549"
$SEC"1"
CDS_SEC"1";
"B"
$PN"2"10;
"A"
$PN"1"81;
%"Q_CAP"
"1","(-125,-1225)","2","pure_quanta","I130";
;
PART_NUMBER"CH4104K1B00"
PACK_TYPE"0402"
TOLERANCE"10%"
VALUE"0.1UF"
VOLTAGE"25V"
MATERIAL"X7R"
$LOCATION"C548"
CDS_LIB"pure_quanta"
CDS_LOCATION"C548"
$SEC"1"
CDS_SEC"1";
"B"
$PN"2"11;
"A"
$PN"1"80;
%"Q_RES"
"2","(725,-1225)","0","pure_quanta","I132";
;
PART_NUMBER"CS07502FB04"
PACK_TYPE"0402LF"
VALUE"75"
TOLERANCE"1%"
MATERIAL"CHIP"
WATTAGE"1/16W"
$LOCATION"R774"
CDS_LIB"pure_quanta"
CDS_LOCATION"R774"
$SEC"1"
CDS_SEC"1";
"A"
$PN"1"86;
"B"
$PN"2"12;
%"UNIVERSAL_GND"
"1","(725,-1475)","0","logical_power","I133";
;
CDS_LIB"logical_power"
HDL_POWER"GND";
"A"12;
%"UNIVERSAL_POWER"
"1","(1750,2725)","0","logical_power","I14";
;
HDL_POWER"P3V3_AUX"
CDS_LIB"logical_power";
"A"6;
%"Q_RES"
"1","(625,-725)","0","pure_quanta","I144";
;
PART_NUMBER"CS03322FB03"
TOLERANCE"1%"
MATERIAL"CHIP"
PACK_TYPE"0402LF"
WATTAGE"1/16W"
VALUE"33.2"
$LOCATION"R1472"
CDS_LIB"pure_quanta"
CDS_LOCATION"R1472"
$SEC"1"
CDS_SEC"1";
"B"
$PN"2"82;
"A"
$PN"1"85;
%"Q_RES"
"1","(625,750)","0","pure_quanta","I148";
;
PART_NUMBER"CS03322FB03"
TOLERANCE"1%"
WATTAGE"1/16W"
VALUE"33.2"
MATERIAL"CHIP"
PACK_TYPE"0402LF"
$LOCATION"R4502"
CDS_LIB"pure_quanta"
CDS_LOCATION"R4502"
$SEC"1"
CDS_SEC"1";
"B"
$PN"2"19;
"A"
$PN"1"17;
%"Q_RES"
"2","(1750,2525)","0","pure_quanta","I15";
;
PART_NUMBER"CS21002FB06"
WATTAGE"1/16W"
TOLERANCE"1%"
VALUE"1K"
MATERIAL"CHIP"
PACK_TYPE"0402LF"
$LOCATION"R778"
CDS_LIB"pure_quanta"
CDS_LOCATION"R778"
$SEC"1"
CDS_SEC"1";
"A"
$PN"1"6;
"B"
$PN"2"21;
%"Q_RES"
"1","(625,700)","0","pure_quanta","I153";
;
PART_NUMBER"CS00002JB13"
MATERIAL"CHIP"
VALUE"0"
$LOCATION"R4503"
CDS_LIB"pure_quanta"
PACK_TYPE"0402LF"
TOLERANCE"5%"
WATTAGE"1/16W"
CDS_LOCATION"R4503"
$SEC"1"
CDS_SEC"1";
"B"
$PN"2"20;
"A"
$PN"1"18;
%"UNIVERSAL_POWER"
"1","(1825,1775)","0","logical_power","I20";
;
HDL_POWER"P3V3_AUX"
CDS_LIB"logical_power";
"A"3;
%"SCONN60_ASP21410801"
"1","(375,2425)","0","pure_quanta","I44";
;
PART_NUMBER"DFHS60FS108"
VALUE"SCONN60_ASP-214108-01"
PART_TYPE"SMLF"
MATERIAL"IO"
$LOCATION"J42"
CDS_LIB"pure_quanta"
NEEDS_NO_SIZE"TRUE"
CDS_LMAN_SYM_OUTLINE"-100,850,100,-850"
CDS_LOCATION"J42"
$SEC"1"
CDS_SEC"1";
"G4"
$PN"G4"8;
"G3"
$PN"G3"9;
"G2"
$PN"G2"8;
"G1"
$PN"G1"9;
"60"
$PN"60"8;
"59"
$PN"59"39;
"58"
$PN"58"8;
"57"
$PN"57"9;
"56"
$PN"56"37;
"55"
$PN"55"38;
"54"
$PN"54"36;
"53"
$PN"53"74;
"52"
$PN"52"3;
"51"
$PN"51"73;
"50"
$PN"50"41;
"49"
$PN"49"72;
"48"
$PN"48"40;
"47"
$PN"47"71;
"46"
$PN"46"42;
"45"
$PN"45"70;
"44"
$PN"44"43;
"43"
$PN"43"69;
"42"
$PN"42"45;
"41"
$PN"41"68;
"40"
$PN"40"44;
"39"
$PN"39"67;
"38"
$PN"38"35;
"37"
$PN"37"66;
"36"
$PN"36"21;
"35"
$PN"35"65;
"34"
$PN"34"48;
"33"
$PN"33"64;
"32"
$PN"32"47;
"31"
$PN"31"63;
"29"
$PN"29"62;
"30"
$PN"30"22;
"28"
$PN"28"23;
"27"
$PN"27"61;
"26"
$PN"26"24;
"25"
$PN"25"60;
"24"
$PN"24"46;
"23"
$PN"23"59;
"22"
$PN"22"25;
"21"
$PN"21"58;
"20"
$PN"20"57;
"19"
$PN"19"56;
"18"
$PN"18"26;
"17"
$PN"17"55;
"16"
$PN"16"8;
"15"
$PN"15"54;
"14"
$PN"14"8;
"13"
$PN"13"53;
"12"
$PN"12"4;
"11"
$PN"11"29;
"10"
$PN"10"52;
"9"
$PN"9"51;
"8"
$PN"8"34;
"7"
$PN"7"30;
"6"
$PN"6"28;
"5"
$PN"5"31;
"4"
$PN"4"50;
"3"
$PN"3"32;
"2"
$PN"2"33;
"1"
$PN"1"5;
%"Q_RES"
"1","(1625,3175)","0","pure_quanta","I5";
;
PART_NUMBER"CS01002FB07"
PACK_TYPE"0402LF"
VALUE"10"
MATERIAL"CHIP"
WATTAGE"1/16W"
TOLERANCE"1%"
$LOCATION"R775"
CDS_LIB"pure_quanta"
CDS_LOCATION"R775"
$SEC"1"
CDS_SEC"1";
"B"
$PN"2"91;
"A"
$PN"1"33;
%"UNIVERSAL_GND"
"1","(25,1500)","0","logical_power","I61";
;
CDS_LIB"logical_power"
HDL_POWER"GND";
"A"9;
%"UNIVERSAL_POWER"
"1","(25,3750)","0","logical_power","I69";
;
HDL_POWER"P1V05_PCH_AUX"
CDS_LIB"logical_power";
"A"5;
%"Q_RES"
"1","(1625,3125)","0","pure_quanta","I7";
;
PART_NUMBER"CS11002FB07"
PACK_TYPE"0402LF"
WATTAGE"1/16W"
MATERIAL"CHIP"
VALUE"100"
TOLERANCE"1%"
$LOCATION"R776"
CDS_LIB"pure_quanta"
CDS_LOCATION"R776"
$SEC"1"
CDS_SEC"1";
"B"
$PN"2"27;
"A"
$PN"1"50;
%"Q_RES"
"1","(-1650,3075)","0","pure_quanta","I70";
;
PART_NUMBER"CS01002FB07"
PACK_TYPE"0402LF"
MATERIAL"CHIP"
WATTAGE"1/16W"
TOLERANCE"1%"
VALUE"10"
$LOCATION"R763"
CDS_LIB"pure_quanta"
CDS_LOCATION"R763"
$SEC"1"
CDS_SEC"1";
"B"
$PN"2"31;
"A"
$PN"1"90;
%"Q_RES"
"1","(-1650,3125)","0","pure_quanta","I71";
;
PART_NUMBER"CS00002JB13"
PACK_TYPE"0402LF"
TOLERANCE"5%"
VALUE"0"
MATERIAL"CHIP"
WATTAGE"1/16W"
$LOCATION"R762"
CDS_LIB"pure_quanta"
CDS_LOCATION"R762"
$SEC"1"
CDS_SEC"1";
"B"
$PN"2"32;
"A"
$PN"1"89;
%"Q_RES"
"1","(-1650,1925)","0","pure_quanta","I74";
;
PART_NUMBER"CS00002JB13"
PACK_TYPE"0402LF"
MATERIAL"CHIP"
TOLERANCE"5%"
VALUE"0"
WATTAGE"1/16W"
$LOCATION"R765"
CDS_LIB"pure_quanta"
CDS_LOCATION"R765"
$SEC"1"
CDS_SEC"1";
"B"
$PN"2"73;
"A"
$PN"1"87;
%"Q_RES"
"1","(-1650,2925)","0","pure_quanta","I83";
;
PART_NUMBER"CS00002JB13"
PACK_TYPE"0402LF"
TOLERANCE"5%"
VALUE"0"
WATTAGE"1/16W"
MATERIAL"CHIP"
$LOCATION"R764"
CDS_LIB"pure_quanta"
CDS_LOCATION"R764"
$SEC"1"
CDS_SEC"1";
"B"
$PN"2"29;
"A"
$PN"1"88;
%"Q_RES"
"1","(2500,2225)","0","pure_quanta","I92";
;
PART_NUMBER"CS04992FB07"
MATERIAL"CHIP"
WATTAGE"1/16W"
PACK_TYPE"0402LF"
TOLERANCE"1%"
VALUE"49.9"
$LOCATION"R780"
CDS_LIB"pure_quanta"
CDS_LOCATION"R780"
$SEC"1"
CDS_SEC"1";
"B"
$PN"2"49;
"A"
$PN"1"35;
%"UNIVERSAL_POWER"
"1","(2200,2725)","0","logical_power","I94";
;
HDL_POWER"PVNN_TERM_CPU0"
CDS_LIB"logical_power";
"A"2;
%"Q_RES"
"2","(2200,2525)","0","pure_quanta","I95";
;
PART_NUMBER"CS11502FB07"
TOLERANCE"1%"
PACK_TYPE"0402LF"
MATERIAL"CHIP"
WATTAGE"1/16W"
VALUE"150"
$LOCATION"R779"
CDS_LIB"pure_quanta"
CDS_LOCATION"R779"
$SEC"1"
CDS_SEC"1";
"A"
$PN"1"2;
"B"
$PN"2"35;
%"Q_CAP"
"1","(2225,2050)","0","pure_quanta","I96";
;
PART_NUMBER"CH4104K1B00"
VALUE"0.1UF"
TOLERANCE"10%"
VOLTAGE"25V"
MATERIAL"X7R"
PACK_TYPE"0402"
$LOCATION"C552"
CDS_LIB"pure_quanta"
CDS_LOCATION"C552"
$SEC"1"
CDS_SEC"1";
"B"
$PN"2"15;
"A"
$PN"1"35;
%"UNIVERSAL_GND"
"1","(2225,1800)","0","logical_power","I97";
;
CDS_LIB"logical_power"
HDL_POWER"GND";
"A"15;
%"UNIVERSAL_GND"
"1","(875,3300)","0","logical_power","I98";
;
CDS_LIB"logical_power"
HDL_POWER"GND";
"A"16;
%"Q_CAP"
"1","(875,3500)","0","pure_quanta","I99";
;
PART_NUMBER"CH5104KEB02"
TOLERANCE"10%"
MATERIAL"X6S"
PACK_TYPE"C0402"
VALUE"1UF"
VOLTAGE"25V"
$LOCATION"C550"
CDS_LIB"pure_quanta"
CDS_LOCATION"C550"
$SEC"1"
CDS_SEC"1";
"B"
$PN"2"16;
"A"
$PN"1"4;
END.
